(kicad_pcb
	(version 20260206)
	(generator "pcbnew")
	(generator_version "10.0")
	(general
		(thickness 1.6)
		(legacy_teardrops no)
	)
	(paper "A4")
	(title_block
		(title "03242023_DA0F0TMBIJ0_F0T_Motherboard_J_brd_V01_OCP.brd")
		(comment 1 "Grand Teton / footprints 2049-2053 of 6105")
	)
	(layers
		(0 "F.Cu" signal "TOP")
		(4 "In1.Cu" signal "GND")
		(6 "In2.Cu" signal "IN1")
		(8 "In3.Cu" signal "GND1")
		(10 "In4.Cu" signal "IN2")
		(12 "In5.Cu" signal "GND2")
		(14 "In6.Cu" signal "IN3")
		(16 "In7.Cu" signal "GND3")
		(18 "In8.Cu" signal "VCC")
		(20 "In9.Cu" signal "VCC1")
		(22 "In10.Cu" signal "GND4")
		(24 "In11.Cu" signal "IN4")
		(26 "In12.Cu" signal "GND5")
		(28 "In13.Cu" signal "IN5")
		(30 "In14.Cu" signal "GND6")
		(32 "In15.Cu" signal "IN6")
		(34 "In16.Cu" signal "GND7")
		(2 "B.Cu" signal "BOTTOM")
		(9 "F.Adhes" user "F.Adhesive")
		(11 "B.Adhes" user "B.Adhesive")
		(13 "F.Paste" user "Package Geometry/Pastemask Top")
		(15 "B.Paste" user "Package Geometry/Pastemask Bottom")
		(5 "F.SilkS" user "Ref Des/Silkscreen Top")
		(7 "B.SilkS" user "Ref Des/Silkscreen Bottom")
		(1 "F.Mask" user "Board Geometry/Soldermask Top")
		(3 "B.Mask" user "Board Geometry/Soldermask Bottom")
		(17 "Dwgs.User" user "User.Drawings")
		(19 "Cmts.User" user "User.Comments")
		(21 "Eco1.User" user "User.Eco1")
		(23 "Eco2.User" user "User.Eco2")
		(25 "Edge.Cuts" user "Board Geometry/Outline")
		(27 "Margin" user)
		(31 "F.CrtYd" user "Package Geometry/Place Bound Top")
		(29 "B.CrtYd" user "Package Geometry/Place Bound Bottom")
		(35 "F.Fab" user "Ref Des/Assembly Top")
		(33 "B.Fab" user "Ref Des/Assembly Bottom")
	)
	(footprint ""
		(layer "F.Cu")
		(at 360.482642 -393.28725)
		(property "Reference" "R4160"
			(at 0 0 0)
			(layer "F.SilkS")
			(hide yes)
			(effects
				(font
					(size 1.27 1.27)
				)
			)
		)
		(property "Value" ""
			(at 0 0 0)
			(layer "F.Fab")
			(effects
				(font
					(size 1.27 1.27)
				)
			)
		)
		(duplicate_pad_numbers_are_jumpers no)
		(fp_line
			(start -0.7874 -0.4064)
			(end 0.7874 -0.4064)
			(stroke
				(width 0.1524)
				(type default)
			)
			(layer "F.SilkS")
		)
		(fp_line
			(start -0.7874 0.4064)
			(end -0.7874 -0.4064)
			(stroke
				(width 0.1524)
				(type default)
			)
			(layer "F.SilkS")
		)
		(fp_line
			(start 0.7874 -0.4064)
			(end 0.7874 0.4064)
			(stroke
				(width 0.1524)
				(type default)
			)
			(layer "F.SilkS")
		)
		(fp_line
			(start 0.7874 0.4064)
			(end -0.7874 0.4064)
			(stroke
				(width 0.1524)
				(type default)
			)
			(layer "F.SilkS")
		)
		(fp_line
			(start -0.67945 -0.305054)
			(end -0.12065 -0.305054)
			(stroke
				(width 0.1)
				(type default)
			)
			(layer "F.Fab")
		)
		(fp_line
			(start -0.67945 0.3048)
			(end -0.67945 -0.305054)
			(stroke
				(width 0.1)
				(type default)
			)
			(layer "F.Fab")
		)
		(fp_line
			(start -0.12065 -0.305054)
			(end -0.12065 -0.2794)
			(stroke
				(width 0.1)
				(type default)
			)
			(layer "F.Fab")
		)
		(fp_line
			(start -0.12065 -0.2794)
			(end 0.12065 -0.2794)
			(stroke
				(width 0.1)
				(type default)
			)
			(layer "F.Fab")
		)
		(fp_line
			(start -0.12065 0.2794)
			(end -0.12065 0.3048)
			(stroke
				(width 0.1)
				(type default)
			)
			(layer "F.Fab")
		)
		(fp_line
			(start -0.12065 0.3048)
			(end -0.67945 0.3048)
			(stroke
				(width 0.1)
				(type default)
			)
			(layer "F.Fab")
		)
		(fp_line
			(start 0.120396 0.2794)
			(end -0.12065 0.2794)
			(stroke
				(width 0.1)
				(type default)
			)
			(layer "F.Fab")
		)
		(fp_line
			(start 0.120396 0.3048)
			(end 0.120396 0.2794)
			(stroke
				(width 0.1)
				(type default)
			)
			(layer "F.Fab")
		)
		(fp_line
			(start 0.12065 -0.3048)
			(end 0.67945 -0.3048)
			(stroke
				(width 0.1)
				(type default)
			)
			(layer "F.Fab")
		)
		(fp_line
			(start 0.12065 -0.2794)
			(end 0.12065 -0.3048)
			(stroke
				(width 0.1)
				(type default)
			)
			(layer "F.Fab")
		)
		(fp_line
			(start 0.67945 -0.3048)
			(end 0.67945 0.3048)
			(stroke
				(width 0.1)
				(type default)
			)
			(layer "F.Fab")
		)
		(fp_line
			(start 0.67945 0.3048)
			(end 0.120396 0.3048)
			(stroke
				(width 0.1)
				(type default)
			)
			(layer "F.Fab")
		)
		(pad "1" smd circle
			(at -0.40005 0)
			(size 0 0)
			(layers "F.Cu" "F.Mask" "F.Paste")
			(net "P3V3_AUX")
		)
		(pad "2" smd circle
			(at 0.40005 0)
			(size 0 0)
			(layers "F.Cu" "F.Mask" "F.Paste")
			(net "GPU_3V3IO_RSVD4")
		)
	)
	(footprint ""
		(layer "F.Cu")
		(at 204.64526 -51.999896)
		(property "Reference" "H112"
			(at -0.64008 -8.82777 0)
			(unlocked yes)
			(layer "F.SilkS")
			(effects
				(font
					(size 0.7874 0.5842)
					(thickness 0.1524)
				)
				(justify left)
			)
		)
		(property "Value" ""
			(at 0 0 0)
			(layer "F.Fab")
			(effects
				(font
					(size 1.27 1.27)
				)
			)
		)
		(duplicate_pad_numbers_are_jumpers no)
		(fp_arc
			(start -5.618226 -5.695188)
			(mid 3.086589 -7.380568)
			(end 7.999984 0)
			(stroke
				(width 0.1524)
				(type default)
			)
			(layer "F.SilkS")
		)
		(fp_arc
			(start 7.999984 0)
			(mid 3.083611 7.381777)
			(end -5.622798 5.690616)
			(stroke
				(width 0.1524)
				(type default)
			)
			(layer "F.SilkS")
		)
		(fp_arc
			(start -3.527044 -7.18058)
			(mid -2.158979 -7.703219)
			(end -0.718566 -7.967726)
			(stroke
				(width 0.1524)
				(type default)
			)
			(layer "B.SilkS")
		)
		(fp_arc
			(start 7.999984 0)
			(mid 3.091799 7.378252)
			(end -5.610098 5.703062)
			(stroke
				(width 0.1524)
				(type default)
			)
			(layer "B.SilkS")
		)
		(fp_circle
			(center 0 0)
			(end 7.999984 0)
			(stroke
				(width 0.1)
				(type default)
			)
			(fill no)
			(layer "B.Fab")
		)
		(fp_circle
			(center 0 0)
			(end 7.999984 0)
			(stroke
				(width 0.1)
				(type default)
			)
			(fill no)
			(layer "F.Fab")
		)
		(pad "" np_thru_hole circle
			(at 0 0)
			(size 5.5118 5.5118)
			(drill 5.5118)
			(layers "*.Cu" "*.Mask")
			(clearance 0.381)
			(thermal_gap 0.381)
		)
		(pad "2" thru_hole circle
			(at 0 -3.999992)
			(size 0.762 0.762)
			(drill 0.5588)
			(layers "*.Cu" "*.Mask")
			(remove_unused_layers no)
			(net "GND")
			(clearance 0.1524)
			(thermal_gap 0.1524)
		)
		(pad "3" thru_hole circle
			(at -2.999994 -2.500122)
			(size 0.762 0.762)
			(drill 0.5588)
			(layers "*.Cu" "*.Mask")
			(remove_unused_layers no)
			(net "GND")
			(clearance 0.1524)
			(thermal_gap 0.1524)
		)
		(pad "4" thru_hole circle
			(at -3.999992 0)
			(size 0.762 0.762)
			(drill 0.5588)
			(layers "*.Cu" "*.Mask")
			(remove_unused_layers no)
			(net "GND")
			(clearance 0.1524)
			(thermal_gap 0.1524)
		)
		(pad "5" thru_hole circle
			(at -2.999994 2.500122)
			(size 0.762 0.762)
			(drill 0.5588)
			(layers "*.Cu" "*.Mask")
			(remove_unused_layers no)
			(net "GND")
			(clearance 0.1524)
			(thermal_gap 0.1524)
		)
		(pad "6" thru_hole circle
			(at 0 3.999992)
			(size 0.762 0.762)
			(drill 0.5588)
			(layers "*.Cu" "*.Mask")
			(remove_unused_layers no)
			(net "GND")
			(clearance 0.1524)
			(thermal_gap 0.1524)
		)
		(pad "7" thru_hole circle
			(at 2.999994 2.500122)
			(size 0.762 0.762)
			(drill 0.5588)
			(layers "*.Cu" "*.Mask")
			(remove_unused_layers no)
			(net "GND")
			(clearance 0.1524)
			(thermal_gap 0.1524)
		)
		(pad "8" thru_hole circle
			(at 3.999992 0)
			(size 0.762 0.762)
			(drill 0.5588)
			(layers "*.Cu" "*.Mask")
			(remove_unused_layers no)
			(net "GND")
			(clearance 0.1524)
			(thermal_gap 0.1524)
		)
		(pad "9" thru_hole circle
			(at 2.999994 -2.500122)
			(size 0.762 0.762)
			(drill 0.5588)
			(layers "*.Cu" "*.Mask")
			(remove_unused_layers no)
			(net "GND")
			(clearance 0.1524)
			(thermal_gap 0.1524)
		)
		(zone
			(layer "F.Cu")
			(hatch none 0.5)
			(connect_pads
				(clearance 0)
			)
			(min_thickness 0.25)
			(keepout
				(tracks not_allowed)
				(vias allowed)
				(pads allowed)
				(copperpour not_allowed)
				(footprints allowed)
			)
			(placement
				(enabled no)
				(sheetname "")
			)
			(fill
				(thermal_gap 0.5)
				(thermal_bridge_width 0.5)
				(island_removal_mode 0)
			)
			(polygon
				(pts
					(arc
						(start 204.64526 -59.99988)
						(mid 198.988417 -57.656739)
						(end 196.645276 -51.999896)
					)
					(arc
						(start 196.645276 -51.999896)
						(mid 198.988417 -46.343053)
						(end 204.64526 -43.999912)
					)
					(xy 204.64526 -46.74616) (xy 204.594206 -46.74616)
					(arc
						(start 204.593952 -46.74616)
						(mid 199.391273 -51.999896)
						(end 204.593952 -57.253632)
					)
					(xy 204.594206 -57.253632) (xy 204.64526 -57.253632)
				)
			)
		)
		(zone
			(layer "F.Cu")
			(hatch none 0.5)
			(connect_pads
				(clearance 0)
			)
			(min_thickness 0.25)
			(keepout
				(tracks not_allowed)
				(vias allowed)
				(pads allowed)
				(copperpour not_allowed)
				(footprints allowed)
			)
			(placement
				(enabled no)
				(sheetname "")
			)
			(fill
				(thermal_gap 0.5)
				(thermal_bridge_width 0.5)
				(island_removal_mode 0)
			)
			(polygon
				(pts
					(arc
						(start 204.64526 -59.99988)
						(mid 210.302103 -57.656739)
						(end 212.645244 -51.999896)
					)
					(arc
						(start 212.645244 -51.999896)
						(mid 210.302103 -46.343053)
						(end 204.64526 -43.999912)
					)
					(xy 204.64526 -46.74616) (xy 204.696314 -46.74616)
					(arc
						(start 204.696568 -46.74616)
						(mid 209.899247 -51.999896)
						(end 204.696568 -57.253632)
					)
					(xy 204.696314 -57.253632) (xy 204.64526 -57.253632)
				)
			)
		)
		(zone
			(layers "F.Cu" "B.Cu" "In1.Cu" "In2.Cu" "In3.Cu" "In4.Cu" "In5.Cu" "In6.Cu"
				"In7.Cu" "In8.Cu" "In9.Cu" "In10.Cu" "In11.Cu" "In12.Cu" "In13.Cu" "In14.Cu"
				"In15.Cu" "In16.Cu"
			)
			(hatch none 0.5)
			(connect_pads
				(clearance 0)
			)
			(min_thickness 0.25)
			(keepout
				(tracks not_allowed)
				(vias allowed)
				(pads allowed)
				(copperpour not_allowed)
				(footprints allowed)
			)
			(placement
				(enabled no)
				(sheetname "")
			)
			(fill
				(thermal_gap 0.5)
				(thermal_bridge_width 0.5)
				(island_removal_mode 0)
			)
			(polygon
				(pts
					(arc
						(start 207.92186 -51.999896)
						(mid 201.36866 -51.999896)
						(end 207.92186 -51.999896)
					)
				)
			)
		)
		(zone
			(layer "B.Cu")
			(hatch none 0.5)
			(connect_pads
				(clearance 0)
			)
			(min_thickness 0.25)
			(keepout
				(tracks not_allowed)
				(vias allowed)
				(pads allowed)
				(copperpour not_allowed)
				(footprints allowed)
			)
			(placement
				(enabled no)
				(sheetname "")
			)
			(fill
				(thermal_gap 0.5)
				(thermal_bridge_width 0.5)
				(island_removal_mode 0)
			)
			(polygon
				(pts
					(arc
						(start 204.64526 -57.507886)
						(mid 199.13727 -51.999896)
						(end 204.64526 -46.491906)
					)
					(arc
						(start 204.64526 -46.974506)
						(mid 199.61987 -51.999896)
						(end 204.64526 -57.025286)
					)
				)
			)
		)
		(zone
			(layer "B.Cu")
			(hatch none 0.5)
			(connect_pads
				(clearance 0)
			)
			(min_thickness 0.25)
			(keepout
				(tracks not_allowed)
				(vias allowed)
				(pads allowed)
				(copperpour not_allowed)
				(footprints allowed)
			)
			(placement
				(enabled no)
				(sheetname "")
			)
			(fill
				(thermal_gap 0.5)
				(thermal_bridge_width 0.5)
				(island_removal_mode 0)
			)
			(polygon
				(pts
					(arc
						(start 204.64526 -57.507886)
						(mid 210.15325 -51.999896)
						(end 204.64526 -46.491906)
					)
					(arc
						(start 204.64526 -46.974506)
						(mid 209.67065 -51.999896)
						(end 204.64526 -57.025286)
					)
				)
			)
		)
	)
	(footprint ""
		(layer "F.Cu")
		(at 133.19252 -121.536968)
		(property "Reference" "R4763"
			(at 0 0 0)
			(layer "F.SilkS")
			(hide yes)
			(effects
				(font
					(size 1.27 1.27)
				)
			)
		)
		(property "Value" ""
			(at 0 0 0)
			(layer "F.Fab")
			(effects
				(font
					(size 1.27 1.27)
				)
			)
		)
		(duplicate_pad_numbers_are_jumpers no)
		(fp_line
			(start -0.7874 -0.4064)
			(end 0.7874 -0.4064)
			(stroke
				(width 0.1524)
				(type default)
			)
			(layer "F.SilkS")
		)
		(fp_line
			(start -0.7874 0.4064)
			(end -0.7874 -0.4064)
			(stroke
				(width 0.1524)
				(type default)
			)
			(layer "F.SilkS")
		)
		(fp_line
			(start 0.7874 -0.4064)
			(end 0.7874 0.4064)
			(stroke
				(width 0.1524)
				(type default)
			)
			(layer "F.SilkS")
		)
		(fp_line
			(start 0.7874 0.4064)
			(end -0.7874 0.4064)
			(stroke
				(width 0.1524)
				(type default)
			)
			(layer "F.SilkS")
		)
		(fp_line
			(start -0.67945 -0.305054)
			(end -0.12065 -0.305054)
			(stroke
				(width 0.1)
				(type default)
			)
			(layer "F.Fab")
		)
		(fp_line
			(start -0.67945 0.3048)
			(end -0.67945 -0.305054)
			(stroke
				(width 0.1)
				(type default)
			)
			(layer "F.Fab")
		)
		(fp_line
			(start -0.12065 -0.305054)
			(end -0.12065 -0.2794)
			(stroke
				(width 0.1)
				(type default)
			)
			(layer "F.Fab")
		)
		(fp_line
			(start -0.12065 -0.2794)
			(end 0.12065 -0.2794)
			(stroke
				(width 0.1)
				(type default)
			)
			(layer "F.Fab")
		)
		(fp_line
			(start -0.12065 0.2794)
			(end -0.12065 0.3048)
			(stroke
				(width 0.1)
				(type default)
			)
			(layer "F.Fab")
		)
		(fp_line
			(start -0.12065 0.3048)
			(end -0.67945 0.3048)
			(stroke
				(width 0.1)
				(type default)
			)
			(layer "F.Fab")
		)
		(fp_line
			(start 0.120396 0.2794)
			(end -0.12065 0.2794)
			(stroke
				(width 0.1)
				(type default)
			)
			(layer "F.Fab")
		)
		(fp_line
			(start 0.120396 0.3048)
			(end 0.120396 0.2794)
			(stroke
				(width 0.1)
				(type default)
			)
			(layer "F.Fab")
		)
		(fp_line
			(start 0.12065 -0.3048)
			(end 0.67945 -0.3048)
			(stroke
				(width 0.1)
				(type default)
			)
			(layer "F.Fab")
		)
		(fp_line
			(start 0.12065 -0.2794)
			(end 0.12065 -0.3048)
			(stroke
				(width 0.1)
				(type default)
			)
			(layer "F.Fab")
		)
		(fp_line
			(start 0.67945 -0.3048)
			(end 0.67945 0.3048)
			(stroke
				(width 0.1)
				(type default)
			)
			(layer "F.Fab")
		)
		(fp_line
			(start 0.67945 0.3048)
			(end 0.120396 0.3048)
			(stroke
				(width 0.1)
				(type default)
			)
			(layer "F.Fab")
		)
		(pad "1" smd circle
			(at -0.40005 0)
			(size 0 0)
			(layers "F.Cu" "F.Mask" "F.Paste")
			(net "P3V3_AUX")
		)
		(pad "2" smd circle
			(at 0.40005 0)
			(size 0 0)
			(layers "F.Cu" "F.Mask" "F.Paste")
			(net "HP_OCP_V3_2_EN")
		)
	)
	(footprint ""
		(layer "F.Cu")
		(at 111.21136 -31.437834 90)
		(property "Reference" "C1823"
			(at 0 0 90)
			(layer "F.SilkS")
			(hide yes)
			(effects
				(font
					(size 1.27 1.27)
				)
			)
		)
		(property "Value" ""
			(at 0 0 90)
			(layer "F.Fab")
			(effects
				(font
					(size 1.27 1.27)
				)
			)
		)
		(duplicate_pad_numbers_are_jumpers no)
		(fp_line
			(start 0.7874 -0.4064)
			(end 0.7874 0.4064)
			(stroke
				(width 0.1524)
				(type default)
			)
			(layer "F.SilkS")
		)
		(fp_line
			(start -0.7874 -0.4064)
			(end 0.7874 -0.4064)
			(stroke
				(width 0.1524)
				(type default)
			)
			(layer "F.SilkS")
		)
		(fp_line
			(start 0.7874 0.4064)
			(end -0.7874 0.4064)
			(stroke
				(width 0.1524)
				(type default)
			)
			(layer "F.SilkS")
		)
		(fp_line
			(start -0.7874 0.4064)
			(end -0.7874 -0.4064)
			(stroke
				(width 0.1524)
				(type default)
			)
			(layer "F.SilkS")
		)
		(fp_line
			(start -0.12065 -0.305054)
			(end -0.12065 -0.2794)
			(stroke
				(width 0.1)
				(type default)
			)
			(layer "F.Fab")
		)
		(fp_line
			(start -0.67945 -0.305054)
			(end -0.12065 -0.305054)
			(stroke
				(width 0.1)
				(type default)
			)
			(layer "F.Fab")
		)
		(fp_line
			(start 0.67945 -0.3048)
			(end 0.67945 0.3048)
			(stroke
				(width 0.1)
				(type default)
			)
			(layer "F.Fab")
		)
		(fp_line
			(start 0.12065 -0.3048)
			(end 0.67945 -0.3048)
			(stroke
				(width 0.1)
				(type default)
			)
			(layer "F.Fab")
		)
		(fp_line
			(start 0.12065 -0.2794)
			(end 0.12065 -0.3048)
			(stroke
				(width 0.1)
				(type default)
			)
			(layer "F.Fab")
		)
		(fp_line
			(start -0.12065 -0.2794)
			(end 0.12065 -0.2794)
			(stroke
				(width 0.1)
				(type default)
			)
			(layer "F.Fab")
		)
		(fp_line
			(start 0.120396 0.2794)
			(end -0.12065 0.2794)
			(stroke
				(width 0.1)
				(type default)
			)
			(layer "F.Fab")
		)
		(fp_line
			(start -0.12065 0.2794)
			(end -0.12065 0.3048)
			(stroke
				(width 0.1)
				(type default)
			)
			(layer "F.Fab")
		)
		(fp_line
			(start 0.67945 0.3048)
			(end 0.120396 0.3048)
			(stroke
				(width 0.1)
				(type default)
			)
			(layer "F.Fab")
		)
		(fp_line
			(start 0.120396 0.3048)
			(end 0.120396 0.2794)
			(stroke
				(width 0.1)
				(type default)
			)
			(layer "F.Fab")
		)
		(fp_line
			(start -0.12065 0.3048)
			(end -0.67945 0.3048)
			(stroke
				(width 0.1)
				(type default)
			)
			(layer "F.Fab")
		)
		(fp_line
			(start -0.67945 0.3048)
			(end -0.67945 -0.305054)
			(stroke
				(width 0.1)
				(type default)
			)
			(layer "F.Fab")
		)
		(pad "1" smd circle
			(at -0.40005 0 90)
			(size 0 0)
			(layers "F.Cu" "F.Mask" "F.Paste")
			(net "P3V3_AUX")
		)
		(pad "2" smd circle
			(at 0.40005 0 90)
			(size 0 0)
			(layers "F.Cu" "F.Mask" "F.Paste")
			(net "GND")
		)
	)
	(footprint ""
		(layer "F.Cu")
		(at 142.486634 -402.371052 -90)
		(property "Reference" "C756"
			(at 0 0 270)
			(layer "F.SilkS")
			(hide yes)
			(effects
				(font
					(size 1.27 1.27)
				)
			)
		)
		(property "Value" ""
			(at 0 0 270)
			(layer "F.Fab")
			(effects
				(font
					(size 1.27 1.27)
				)
			)
		)
		(duplicate_pad_numbers_are_jumpers no)
		(fp_line
			(start -0.299974 0.150114)
			(end -0.299974 -0.150114)
			(stroke
				(width 0.1)
				(type default)
			)
			(layer "F.Fab")
		)
		(fp_line
			(start 0.299974 0.150114)
			(end -0.299974 0.150114)
			(stroke
				(width 0.1)
				(type default)
			)
			(layer "F.Fab")
		)
		(fp_line
			(start -0.299974 -0.150114)
			(end 0.299974 -0.150114)
			(stroke
				(width 0.1)
				(type default)
			)
			(layer "F.Fab")
		)
		(fp_line
			(start 0.299974 -0.150114)
			(end 0.299974 0.150114)
			(stroke
				(width 0.1)
				(type default)
			)
			(layer "F.Fab")
		)
		(pad "1" smd rect
			(at -0.2667 0 270)
			(size 0.3048 0.381)
			(layers "F.Cu" "F.Mask" "F.Paste")
			(net "P5E_CPU1_PE2_TX_C_DN<8>")
		)
		(pad "2" smd rect
			(at 0.2667 0 270)
			(size 0.3048 0.381)
			(layers "F.Cu" "F.Mask" "F.Paste")
			(net "P5E_CPU1_PE2_TX_DN<8>")
		)
	)
)
